#ISCELL
  mstr_misc dns *
  *
#ISCELL
  pure_quanta quanta_title_block_c *
  *
#ISCELL
  standard offpage *
  page299_i1
#ISCELL
  logical_power universal_power *
  page299_i10
#ISCELL
  logical_power universal_gnd *
  page299_i11
#ISCELL
  standard offpage *
  page299_i12
#CELL
  pure_quanta q_cap *
  page299_i129
#CELL
  pure_quanta q_res *
  page299_i130
#CELL
  pure_quanta q_res *
  page299_i131
#CELL
  pure_quanta q_res *
  page299_i132
#CELL
  pure_quanta q_res *
  page299_i133
#CELL
  pure_quanta q_res *
  page299_i134
#CELL
  pure_quanta mosfet_nch_dual *
  page299_i135
#ISCELL
  logical_power universal_power *
  page299_i138
#ISCELL
  logical_power universal_gnd *
  page299_i139
#ISCELL
  standard offpage *
  page299_i143
#CELL
  pure_quanta q_res *
  page299_i144
#CELL
  pure_quanta q_res *
  page299_i145
#ISCELL
  logical_power universal_gnd *
  page299_i146
#CELL
  pure_quanta q_res *
  page299_i147
#ISCELL
  logical_power universal_gnd *
  page299_i148
#ISCELL
  standard offpage *
  page299_i149
#ISCELL
  logical_power universal_power *
  page299_i15
#ISCELL
  logical_power universal_power *
  page299_i150
#ISCELL
  standard offpage *
  page299_i151
#CELL
  pure_quanta q_cap *
  page299_i152
#ISCELL
  logical_power universal_gnd *
  page299_i153
#CELL
  pure_quanta q_res *
  page299_i154
#ISCELL
  logical_power universal_power *
  page299_i155
#ISCELL
  logical_power universal_gnd *
  page299_i156
#CELL
  pure_quanta mosfet_nch_dual *
  page299_i157
#CELL
  pure_quanta q_res *
  page299_i158
#ISCELL
  logical_power universal_gnd *
  page299_i159
#ISCELL
  logical_power universal_gnd *
  page299_i16
#CELL
  pure_quanta mosfet_nch_dual *
  page299_i160
#ISCELL
  logical_power universal_power *
  page299_i161
#CELL
  pure_quanta q_res *
  page299_i163
#ISCELL
  logical_power universal_gnd *
  page299_i164
#ISCELL
  standard offpage *
  page299_i165
#CELL
  pure_quanta q_res *
  page299_i166
#CELL
  pure_quanta q_res *
  page299_i167
#CELL
  pure_quanta mosfet_nch_dual *
  page299_i168
#CELL
  pure_quanta mosfet_nch_dual *
  page299_i169
#CELL
  pure_quanta q_res *
  page299_i17
#ISCELL
  standard offpage *
  page299_i170
#CELL
  pure_quanta q_cap *
  page299_i171
#ISCELL
  logical_power universal_gnd *
  page299_i172
#ISCELL
  logical_power universal_power *
  page299_i173
#CELL
  pure_quanta q_res *
  page299_i174
#ISCELL
  logical_power universal_gnd *
  page299_i175
#ISCELL
  logical_power universal_power *
  page299_i176
#CELL
  pure_quanta q_res *
  page299_i177
#ISCELL
  logical_power universal_gnd *
  page299_i178
#ISCELL
  logical_power universal_power *
  page299_i179
#ISCELL
  standard offpage *
  page299_i18
#CELL
  pure_quanta q_res *
  page299_i181
#ISCELL
  logical_power universal_gnd *
  page299_i182
#ISCELL
  standard offpage *
  page299_i183
#CELL
  pure_quanta q_res *
  page299_i184
#ISCELL
  standard offpage *
  page299_i185
#ISCELL
  logical_power universal_gnd *
  page299_i2
#ISCELL
  logical_power universal_power *
  page299_i20
#CELL
  pure_quanta mosfet_nch_dual *
  page299_i21
#ISCELL
  logical_power universal_gnd *
  page299_i22
#CELL
  pure_quanta q_res *
  page299_i23
#ISCELL
  logical_power universal_power *
  page299_i24
#ISCELL
  logical_power universal_gnd *
  page299_i25
#CELL
  pure_quanta mosfet_nch_dual *
  page299_i26
#CELL
  pure_quanta q_res *
  page299_i27
#ISCELL
  logical_power universal_power *
  page299_i28
#ISCELL
  logical_power universal_gnd *
  page299_i29
#CELL
  pure_quanta q_res *
  page299_i3
#CELL
  pure_quanta q_cap *
  page299_i30
#ISCELL
  standard offpage *
  page299_i31
#CELL
  pure_quanta mosfet_nch_dual *
  page299_i37
#ISCELL
  logical_power universal_gnd *
  page299_i38
#CELL
  pure_quanta q_res *
  page299_i39
#CELL
  pure_quanta mosfet_nch_dual *
  page299_i40
#ISCELL
  logical_power universal_power *
  page299_i41
#ISCELL
  logical_power universal_gnd *
  page299_i42
#CELL
  pure_quanta mosfet_nch_dual *
  page299_i43
#ISCELL
  logical_power universal_gnd *
  page299_i44
#CELL
  pure_quanta q_res *
  page299_i45
#ISCELL
  logical_power universal_power *
  page299_i46
#ISCELL
  logical_power universal_gnd *
  page299_i47
#CELL
  pure_quanta mosfet_nch_dual *
  page299_i48
#CELL
  pure_quanta q_res *
  page299_i49
#ISCELL
  logical_power universal_power *
  page299_i5
#ISCELL
  logical_power universal_power *
  page299_i50
#ISCELL
  logical_power universal_gnd *
  page299_i51
#CELL
  pure_quanta mosfet_nch_dual *
  page299_i52
#CELL
  pure_quanta q_res *
  page299_i53
#ISCELL
  logical_power universal_power *
  page299_i54
#CELL
  pure_quanta q_res *
  page299_i55
#ISCELL
  logical_power universal_power *
  page299_i56
#CELL
  pure_quanta mosfet_nch_dual *
  page299_i57
#ISCELL
  logical_power universal_gnd *
  page299_i58
#CELL
  pure_quanta q_res *
  page299_i59
#ISCELL
  standard offpage *
  page299_i6
#ISCELL
  logical_power universal_gnd *
  page299_i60
#ISCELL
  logical_power universal_gnd *
  page299_i61
#ISCELL
  standard offpage *
  page299_i62
#ISCELL
  logical_power universal_gnd *
  page299_i7
#CELL
  pure_quanta q_cap *
  page299_i71
#ISCELL
  standard offpage *
  page299_i72
#ISCELL
  logical_power universal_gnd *
  page299_i73
#CELL
  pure_quanta q_cap *
  page299_i74
#ISCELL
  standard offpage *
  page299_i75
#ISCELL
  logical_power universal_power *
  page299_i83
